(kicad_pcb
	(version 20241229)
	(generator "pcbnew")
	(generator_version "9.0")
	(general
		(thickness 1.61)
		(legacy_teardrops no)
	)
	(paper "A3")
	(title_block
		(title "SO-DIMM DDR5 Tester")
		(date "2025-11-26")
		(rev "1.3.0")
		(comment 9 "footprint 147 of 627 (J2), pads 173-258 of 266")
	)
	(layers
		(0 "F.Cu" signal)
		(4 "In1.Cu" power)
		(6 "In2.Cu" mixed)
		(8 "In3.Cu" power)
		(10 "In4.Cu" mixed)
		(12 "In5.Cu" power)
		(14 "In6.Cu" mixed)
		(16 "In7.Cu" power)
		(18 "In8.Cu" power)
		(20 "In9.Cu" mixed)
		(22 "In10.Cu" power)
		(2 "B.Cu" signal)
		(9 "F.Adhes" user "F.Adhesive")
		(11 "B.Adhes" user "B.Adhesive")
		(13 "F.Paste" user)
		(15 "B.Paste" user)
		(5 "F.SilkS" user "F.Silkscreen")
		(7 "B.SilkS" user "B.Silkscreen")
		(1 "F.Mask" user)
		(3 "B.Mask" user)
		(17 "Dwgs.User" user "User.Drawings")
		(19 "Cmts.User" user "User.Comments")
		(21 "Eco1.User" user "User.Eco1")
		(23 "Eco2.User" user "User.Eco2")
		(25 "Edge.Cuts" user)
		(27 "Margin" user)
		(31 "F.CrtYd" user "F.Courtyard")
		(29 "B.CrtYd" user "B.Courtyard")
		(35 "F.Fab" user)
		(33 "B.Fab" user)
	)
	(footprint "antmicro-footprints:Bus_DDR5_SODIMM_Amphenol_10161033-002RHLF"
		(layer "F.Cu")
		(at 139.780001 134.8375 180)
		(property "Reference" "J2"
			(at -35.119999 -13.0625 180)
			(layer "F.SilkS")
			(effects
				(font
					(size 0.7 0.7)
					(thickness 0.15)
				)
				(justify left bottom)
			)
		)
		(property "Value" "Bus_DDR5_SODIMM_Amphenol_10161033-002RHLF_CUSTOM_2xDetectPin"
			(at 0 13.5 180)
			(layer "F.Fab")
			(effects
				(font
					(size 0.7 0.7)
					(thickness 0.15)
				)
				(justify left bottom)
			)
		)
		(property "Datasheet" "https://cdn.amphenol-cs.com/media/wysiwyg/files/documentation/datasheet/ssio/ssio_ddr5_sodimm.pdf"
			(at 0 0 180)
			(layer "F.Fab")
			(hide yes)
			(effects
				(font
					(size 1.27 1.27)
					(thickness 0.15)
				)
			)
		)
		(property "Author" "Antmicro"
			(at 279.560002 269.675 0)
			(layer "F.Fab")
			(hide yes)
			(effects
				(font
					(size 1 1)
					(thickness 0.15)
				)
			)
		)
		(property "License" "Apache-2.0"
			(at 279.560002 269.675 0)
			(layer "F.Fab")
			(hide yes)
			(effects
				(font
					(size 1 1)
					(thickness 0.15)
				)
			)
		)
		(property "MPN" "10161033-002RHLF"
			(at 279.560002 269.675 0)
			(layer "F.Fab")
			(hide yes)
			(effects
				(font
					(size 1 1)
					(thickness 0.15)
				)
			)
		)
		(property "Manufacturer" "Amphenol"
			(at 279.560002 269.675 0)
			(layer "F.Fab")
			(hide yes)
			(effects
				(font
					(size 1 1)
					(thickness 0.15)
				)
			)
		)
		(sheetname "/DDR5 SODIMM/")
		(sheetfile "ddr5-sodimm.kicad_sch")
		(attr smd)
		(pad "171" smd rect
			(at -10.62 -11.365 180)
			(size 0.3 1.5)
			(layers "F.Cu" "F.Mask" "F.Paste")
			(net 191 "/DDR5 SODIMM/B.DQS4_P")
			(pinfunction "DQS4_B_T")
			(pintype "passive")
		)
		(pad "172" smd rect
			(at -10.87 -3.965 180)
			(size 0.3 1.5)
			(layers "F.Cu" "F.Mask" "F.Paste")
			(net 192 "/DDR5 SODIMM/B.CB1")
			(pinfunction "CB1_B")
			(pintype "passive")
		)
		(pad "173" smd rect
			(at -11.12 -11.365 180)
			(size 0.3 1.5)
			(layers "F.Cu" "F.Mask" "F.Paste")
			(net 1 "GND")
			(pinfunction "VSS")
			(pintype "passive")
		)
		(pad "174" smd rect
			(at -11.37 -3.965 180)
			(size 0.3 1.5)
			(layers "F.Cu" "F.Mask" "F.Paste")
			(net 1 "GND")
			(pinfunction "VSS")
			(pintype "passive")
		)
		(pad "175" smd rect
			(at -11.62 -11.365 180)
			(size 0.3 1.5)
			(layers "F.Cu" "F.Mask" "F.Paste")
			(net 193 "/DDR5 SODIMM/B.CB3")
			(pinfunction "CB3_B")
			(pintype "passive")
		)
		(pad "176" smd rect
			(at -11.87 -3.965 180)
			(size 0.3 1.5)
			(layers "F.Cu" "F.Mask" "F.Paste")
			(net 194 "/DDR5 SODIMM/B.CB2")
			(pinfunction "CB2_B")
			(pintype "passive")
		)
		(pad "177" smd rect
			(at -12.12 -11.365 180)
			(size 0.3 1.5)
			(layers "F.Cu" "F.Mask" "F.Paste")
			(net 1 "GND")
			(pinfunction "VSS")
			(pintype "passive")
		)
		(pad "178" smd rect
			(at -12.37 -3.965 180)
			(size 0.3 1.5)
			(layers "F.Cu" "F.Mask" "F.Paste")
			(net 1 "GND")
			(pinfunction "VSS")
			(pintype "passive")
		)
		(pad "179" smd rect
			(at -12.62 -11.365 180)
			(size 0.3 1.5)
			(layers "F.Cu" "F.Mask" "F.Paste")
			(net 195 "/DDR5 SODIMM/B.DQ0")
			(pinfunction "DQ0_B")
			(pintype "passive")
		)
		(pad "180" smd rect
			(at -12.87 -3.965 180)
			(size 0.3 1.5)
			(layers "F.Cu" "F.Mask" "F.Paste")
			(net 196 "/DDR5 SODIMM/B.DQ1")
			(pinfunction "DQ1_B")
			(pintype "passive")
		)
		(pad "181" smd rect
			(at -13.12 -11.365 180)
			(size 0.3 1.5)
			(layers "F.Cu" "F.Mask" "F.Paste")
			(net 1 "GND")
			(pinfunction "VSS")
			(pintype "passive")
		)
		(pad "182" smd rect
			(at -13.37 -3.965 180)
			(size 0.3 1.5)
			(layers "F.Cu" "F.Mask" "F.Paste")
			(net 1 "GND")
			(pinfunction "VSS")
			(pintype "passive")
		)
		(pad "183" smd rect
			(at -13.62 -11.365 180)
			(size 0.3 1.5)
			(layers "F.Cu" "F.Mask" "F.Paste")
			(net 197 "/DDR5 SODIMM/B.DQ2")
			(pinfunction "DQ2_B")
			(pintype "passive")
		)
		(pad "184" smd rect
			(at -13.87 -3.965 180)
			(size 0.3 1.5)
			(layers "F.Cu" "F.Mask" "F.Paste")
			(net 198 "/DDR5 SODIMM/B.DQ3")
			(pinfunction "DQ3_B")
			(pintype "passive")
		)
		(pad "185" smd rect
			(at -14.12 -11.365 180)
			(size 0.3 1.5)
			(layers "F.Cu" "F.Mask" "F.Paste")
			(net 1 "GND")
			(pinfunction "VSS")
			(pintype "passive")
		)
		(pad "186" smd rect
			(at -14.37 -3.965 180)
			(size 0.3 1.5)
			(layers "F.Cu" "F.Mask" "F.Paste")
			(net 1 "GND")
			(pinfunction "VSS")
			(pintype "passive")
		)
		(pad "187" smd rect
			(at -14.62 -11.365 180)
			(size 0.3 1.5)
			(layers "F.Cu" "F.Mask" "F.Paste")
			(net 202 "/DDR5 SODIMM/B.~{DM0}")
			(pinfunction "DM0_B_n")
			(pintype "passive")
		)
		(pad "188" smd rect
			(at -14.87 -3.965 180)
			(size 0.3 1.5)
			(layers "F.Cu" "F.Mask" "F.Paste")
			(net 203 "/DDR5 SODIMM/B.DQS0_N")
			(pinfunction "DQS0_B_C")
			(pintype "passive")
		)
		(pad "189" smd rect
			(at -15.12 -11.365 180)
			(size 0.3 1.5)
			(layers "F.Cu" "F.Mask" "F.Paste")
			(net 1 "GND")
			(pinfunction "VSS")
			(pintype "passive")
		)
		(pad "190" smd rect
			(at -15.37 -3.965 180)
			(size 0.3 1.5)
			(layers "F.Cu" "F.Mask" "F.Paste")
			(net 204 "/DDR5 SODIMM/B.DQS0_P")
			(pinfunction "DQS0_B_t")
			(pintype "passive")
		)
		(pad "191" smd rect
			(at -15.62 -11.365 180)
			(size 0.3 1.5)
			(layers "F.Cu" "F.Mask" "F.Paste")
			(net 205 "/DDR5 SODIMM/B.DQ4")
			(pinfunction "DQ4_B")
			(pintype "passive")
		)
		(pad "192" smd rect
			(at -15.87 -3.965 180)
			(size 0.3 1.5)
			(layers "F.Cu" "F.Mask" "F.Paste")
			(net 1 "GND")
			(pinfunction "VSS")
			(pintype "passive")
		)
		(pad "193" smd rect
			(at -16.12 -11.365 180)
			(size 0.3 1.5)
			(layers "F.Cu" "F.Mask" "F.Paste")
			(net 1 "GND")
			(pinfunction "VSS")
			(pintype "passive")
		)
		(pad "194" smd rect
			(at -16.37 -3.965 180)
			(size 0.3 1.5)
			(layers "F.Cu" "F.Mask" "F.Paste")
			(net 212 "/DDR5 SODIMM/B.DQ5")
			(pinfunction "DQ5_B")
			(pintype "passive")
		)
		(pad "195" smd rect
			(at -16.62 -11.365 180)
			(size 0.3 1.5)
			(layers "F.Cu" "F.Mask" "F.Paste")
			(net 213 "/DDR5 SODIMM/B.DQ6")
			(pinfunction "DQ6_B")
			(pintype "passive")
		)
		(pad "196" smd rect
			(at -16.87 -3.965 180)
			(size 0.3 1.5)
			(layers "F.Cu" "F.Mask" "F.Paste")
			(net 1 "GND")
			(pinfunction "VSS")
			(pintype "passive")
		)
		(pad "197" smd rect
			(at -17.12 -11.365 180)
			(size 0.3 1.5)
			(layers "F.Cu" "F.Mask" "F.Paste")
			(net 1 "GND")
			(pinfunction "VSS")
			(pintype "passive")
		)
		(pad "198" smd rect
			(at -17.37 -3.965 180)
			(size 0.3 1.5)
			(layers "F.Cu" "F.Mask" "F.Paste")
			(net 219 "/DDR5 SODIMM/B.DQ7")
			(pinfunction "DQ7_B")
			(pintype "passive")
		)
		(pad "199" smd rect
			(at -17.62 -11.365 180)
			(size 0.3 1.5)
			(layers "F.Cu" "F.Mask" "F.Paste")
			(net 228 "/DDR5 SODIMM/B.DQ8")
			(pinfunction "DQ8_B")
			(pintype "passive")
		)
		(pad "200" smd rect
			(at -17.87 -3.965 180)
			(size 0.3 1.5)
			(layers "F.Cu" "F.Mask" "F.Paste")
			(net 1 "GND")
			(pinfunction "VSS")
			(pintype "passive")
		)
		(pad "201" smd rect
			(at -18.12 -11.365 180)
			(size 0.3 1.5)
			(layers "F.Cu" "F.Mask" "F.Paste")
			(net 1 "GND")
			(pinfunction "VSS")
			(pintype "passive")
		)
		(pad "202" smd rect
			(at -18.37 -3.965 180)
			(size 0.3 1.5)
			(layers "F.Cu" "F.Mask" "F.Paste")
			(net 233 "/DDR5 SODIMM/B.DQ9")
			(pinfunction "DQ9_B")
			(pintype "passive")
		)
		(pad "203" smd rect
			(at -18.62 -11.365 180)
			(size 0.3 1.5)
			(layers "F.Cu" "F.Mask" "F.Paste")
			(net 238 "/DDR5 SODIMM/B.DQ10")
			(pinfunction "DQ10_B")
			(pintype "passive")
		)
		(pad "204" smd rect
			(at -18.87 -3.965 180)
			(size 0.3 1.5)
			(layers "F.Cu" "F.Mask" "F.Paste")
			(net 1 "GND")
			(pinfunction "VSS")
			(pintype "passive")
		)
		(pad "205" smd rect
			(at -19.12 -11.365 180)
			(size 0.3 1.5)
			(layers "F.Cu" "F.Mask" "F.Paste")
			(net 1 "GND")
			(pinfunction "VSS")
			(pintype "passive")
		)
		(pad "206" smd rect
			(at -19.37 -3.965 180)
			(size 0.3 1.5)
			(layers "F.Cu" "F.Mask" "F.Paste")
			(net 247 "/DDR5 SODIMM/B.DQ11")
			(pinfunction "DQ11_B")
			(pintype "passive")
		)
		(pad "207" smd rect
			(at -19.62 -11.365 180)
			(size 0.3 1.5)
			(layers "F.Cu" "F.Mask" "F.Paste")
			(net 250 "/DDR5 SODIMM/B.DQS1_N")
			(pinfunction "DQS1_B_C")
			(pintype "passive")
		)
		(pad "208" smd rect
			(at -19.87 -3.965 180)
			(size 0.3 1.5)
			(layers "F.Cu" "F.Mask" "F.Paste")
			(net 1 "GND")
			(pinfunction "VSS")
			(pintype "passive")
		)
		(pad "209" smd rect
			(at -20.12 -11.365 180)
			(size 0.3 1.5)
			(layers "F.Cu" "F.Mask" "F.Paste")
			(net 253 "/DDR5 SODIMM/B.DQS1_P")
			(pinfunction "DQS1_B_t")
			(pintype "passive")
		)
		(pad "210" smd rect
			(at -20.37 -3.965 180)
			(size 0.3 1.5)
			(layers "F.Cu" "F.Mask" "F.Paste")
			(net 254 "/DDR5 SODIMM/B.~{DM1}")
			(pinfunction "DM1_B_n")
			(pintype "passive")
		)
		(pad "211" smd rect
			(at -20.62 -11.365 180)
			(size 0.3 1.5)
			(layers "F.Cu" "F.Mask" "F.Paste")
			(net 1 "GND")
			(pinfunction "VSS")
			(pintype "passive")
		)
		(pad "212" smd rect
			(at -20.87 -3.965 180)
			(size 0.3 1.5)
			(layers "F.Cu" "F.Mask" "F.Paste")
			(net 1 "GND")
			(pinfunction "VSS")
			(pintype "passive")
		)
		(pad "213" smd rect
			(at -21.12 -11.365 180)
			(size 0.3 1.5)
			(layers "F.Cu" "F.Mask" "F.Paste")
			(net 255 "/DDR5 SODIMM/B.DQ12")
			(pinfunction "DQ12_B")
			(pintype "passive")
		)
		(pad "214" smd rect
			(at -21.37 -3.965 180)
			(size 0.3 1.5)
			(layers "F.Cu" "F.Mask" "F.Paste")
			(net 256 "/DDR5 SODIMM/B.DQ13")
			(pinfunction "DQ13_B")
			(pintype "passive")
		)
		(pad "215" smd rect
			(at -21.62 -11.365 180)
			(size 0.3 1.5)
			(layers "F.Cu" "F.Mask" "F.Paste")
			(net 1 "GND")
			(pinfunction "VSS")
			(pintype "passive")
		)
		(pad "216" smd rect
			(at -21.87 -3.965 180)
			(size 0.3 1.5)
			(layers "F.Cu" "F.Mask" "F.Paste")
			(net 1 "GND")
			(pinfunction "VSS")
			(pintype "passive")
		)
		(pad "217" smd rect
			(at -22.12 -11.365 180)
			(size 0.3 1.5)
			(layers "F.Cu" "F.Mask" "F.Paste")
			(net 257 "/DDR5 SODIMM/B.DQ14")
			(pinfunction "DQ14_B")
			(pintype "passive")
		)
		(pad "218" smd rect
			(at -22.37 -3.965 180)
			(size 0.3 1.5)
			(layers "F.Cu" "F.Mask" "F.Paste")
			(net 258 "/DDR5 SODIMM/B.DQ15")
			(pinfunction "DQ15_B")
			(pintype "passive")
		)
		(pad "219" smd rect
			(at -22.62 -11.365 180)
			(size 0.3 1.5)
			(layers "F.Cu" "F.Mask" "F.Paste")
			(net 1 "GND")
			(pinfunction "VSS")
			(pintype "passive")
		)
		(pad "220" smd rect
			(at -22.87 -3.965 180)
			(size 0.3 1.5)
			(layers "F.Cu" "F.Mask" "F.Paste")
			(net 1 "GND")
			(pinfunction "VSS")
			(pintype "passive")
		)
		(pad "221" smd rect
			(at -23.12 -11.365 180)
			(size 0.3 1.5)
			(layers "F.Cu" "F.Mask" "F.Paste")
			(net 259 "/DDR5 SODIMM/B.DQ16")
			(pinfunction "DQ16_B")
			(pintype "passive")
		)
		(pad "222" smd rect
			(at -23.37 -3.965 180)
			(size 0.3 1.5)
			(layers "F.Cu" "F.Mask" "F.Paste")
			(net 260 "/DDR5 SODIMM/B.DQ17")
			(pinfunction "DQ17_B")
			(pintype "passive")
		)
		(pad "223" smd rect
			(at -23.62 -11.365 180)
			(size 0.3 1.5)
			(layers "F.Cu" "F.Mask" "F.Paste")
			(net 1 "GND")
			(pinfunction "VSS")
			(pintype "passive")
		)
		(pad "224" smd rect
			(at -23.87 -3.965 180)
			(size 0.3 1.5)
			(layers "F.Cu" "F.Mask" "F.Paste")
			(net 1 "GND")
			(pinfunction "VSS")
			(pintype "passive")
		)
		(pad "225" smd rect
			(at -24.12 -11.365 180)
			(size 0.3 1.5)
			(layers "F.Cu" "F.Mask" "F.Paste")
			(net 261 "/DDR5 SODIMM/B.DQ18")
			(pinfunction "DQ18_B")
			(pintype "passive")
		)
		(pad "226" smd rect
			(at -24.37 -3.965 180)
			(size 0.3 1.5)
			(layers "F.Cu" "F.Mask" "F.Paste")
			(net 262 "/DDR5 SODIMM/B.DQ19")
			(pinfunction "DQ19_B")
			(pintype "passive")
		)
		(pad "227" smd rect
			(at -24.62 -11.365 180)
			(size 0.3 1.5)
			(layers "F.Cu" "F.Mask" "F.Paste")
			(net 1 "GND")
			(pinfunction "VSS")
			(pintype "passive")
		)
		(pad "228" smd rect
			(at -24.87 -3.965 180)
			(size 0.3 1.5)
			(layers "F.Cu" "F.Mask" "F.Paste")
			(net 1 "GND")
			(pinfunction "VSS")
			(pintype "passive")
		)
		(pad "229" smd rect
			(at -25.12 -11.365 180)
			(size 0.3 1.5)
			(layers "F.Cu" "F.Mask" "F.Paste")
			(net 264 "/DDR5 SODIMM/B.~{DM2}")
			(pinfunction "DM2_B_n")
			(pintype "passive")
		)
		(pad "230" smd rect
			(at -25.37 -3.965 180)
			(size 0.3 1.5)
			(layers "F.Cu" "F.Mask" "F.Paste")
			(net 265 "/DDR5 SODIMM/B.DQS2_N")
			(pinfunction "DQS2_B_C")
			(pintype "passive")
		)
		(pad "231" smd rect
			(at -25.62 -11.365 180)
			(size 0.3 1.5)
			(layers "F.Cu" "F.Mask" "F.Paste")
			(net 1 "GND")
			(pinfunction "VSS")
			(pintype "passive")
		)
		(pad "232" smd rect
			(at -25.87 -3.965 180)
			(size 0.3 1.5)
			(layers "F.Cu" "F.Mask" "F.Paste")
			(net 266 "/DDR5 SODIMM/B.DQS2_P")
			(pinfunction "DQS2_B_t")
			(pintype "passive")
		)
		(pad "233" smd rect
			(at -26.12 -11.365 180)
			(size 0.3 1.5)
			(layers "F.Cu" "F.Mask" "F.Paste")
			(net 268 "/DDR5 SODIMM/B.DQ20")
			(pinfunction "DQ20_B")
			(pintype "passive")
		)
		(pad "234" smd rect
			(at -26.37 -3.965 180)
			(size 0.3 1.5)
			(layers "F.Cu" "F.Mask" "F.Paste")
			(net 1 "GND")
			(pinfunction "VSS")
			(pintype "passive")
		)
		(pad "235" smd rect
			(at -26.62 -11.365 180)
			(size 0.3 1.5)
			(layers "F.Cu" "F.Mask" "F.Paste")
			(net 1 "GND")
			(pinfunction "VSS")
			(pintype "passive")
		)
		(pad "236" smd rect
			(at -26.87 -3.965 180)
			(size 0.3 1.5)
			(layers "F.Cu" "F.Mask" "F.Paste")
			(net 269 "/DDR5 SODIMM/B.DQ21")
			(pinfunction "DQ21_B")
			(pintype "passive")
		)
		(pad "237" smd rect
			(at -27.12 -11.365 180)
			(size 0.3 1.5)
			(layers "F.Cu" "F.Mask" "F.Paste")
			(net 270 "/DDR5 SODIMM/B.DQ22")
			(pinfunction "DQ22_B")
			(pintype "passive")
		)
		(pad "238" smd rect
			(at -27.37 -3.965 180)
			(size 0.3 1.5)
			(layers "F.Cu" "F.Mask" "F.Paste")
			(net 1 "GND")
			(pinfunction "VSS")
			(pintype "passive")
		)
		(pad "239" smd rect
			(at -27.62 -11.365 180)
			(size 0.3 1.5)
			(layers "F.Cu" "F.Mask" "F.Paste")
			(net 1 "GND")
			(pinfunction "VSS")
			(pintype "passive")
		)
		(pad "240" smd rect
			(at -27.87 -3.965 180)
			(size 0.3 1.5)
			(layers "F.Cu" "F.Mask" "F.Paste")
			(net 271 "/DDR5 SODIMM/B.DQ23")
			(pinfunction "DQ23_B")
			(pintype "passive")
		)
		(pad "241" smd rect
			(at -28.12 -11.365 180)
			(size 0.3 1.5)
			(layers "F.Cu" "F.Mask" "F.Paste")
			(net 275 "/DDR5 SODIMM/B.DQ24")
			(pinfunction "DQ24_B")
			(pintype "passive")
		)
		(pad "242" smd rect
			(at -28.37 -3.965 180)
			(size 0.3 1.5)
			(layers "F.Cu" "F.Mask" "F.Paste")
			(net 1 "GND")
			(pinfunction "VSS")
			(pintype "passive")
		)
		(pad "243" smd rect
			(at -28.62 -11.365 180)
			(size 0.3 1.5)
			(layers "F.Cu" "F.Mask" "F.Paste")
			(net 1 "GND")
			(pinfunction "VSS")
			(pintype "passive")
		)
		(pad "244" smd rect
			(at -28.87 -3.965 180)
			(size 0.3 1.5)
			(layers "F.Cu" "F.Mask" "F.Paste")
			(net 276 "/DDR5 SODIMM/B.DQ25")
			(pinfunction "DQ25_B")
			(pintype "passive")
		)
		(pad "245" smd rect
			(at -29.12 -11.365 180)
			(size 0.3 1.5)
			(layers "F.Cu" "F.Mask" "F.Paste")
			(net 277 "/DDR5 SODIMM/B.DQ26")
			(pinfunction "DQ26_B")
			(pintype "passive")
		)
		(pad "246" smd rect
			(at -29.37 -3.965 180)
			(size 0.3 1.5)
			(layers "F.Cu" "F.Mask" "F.Paste")
			(net 1 "GND")
			(pinfunction "VSS")
			(pintype "passive")
		)
		(pad "247" smd rect
			(at -29.62 -11.365 180)
			(size 0.3 1.5)
			(layers "F.Cu" "F.Mask" "F.Paste")
			(net 1 "GND")
			(pinfunction "VSS")
			(pintype "passive")
		)
		(pad "248" smd rect
			(at -29.87 -3.965 180)
			(size 0.3 1.5)
			(layers "F.Cu" "F.Mask" "F.Paste")
			(net 278 "/DDR5 SODIMM/B.DQ27")
			(pinfunction "DQ27_B")
			(pintype "passive")
		)
		(pad "249" smd rect
			(at -30.12 -11.365 180)
			(size 0.3 1.5)
			(layers "F.Cu" "F.Mask" "F.Paste")
			(net 279 "/DDR5 SODIMM/B.DQS3_N")
			(pinfunction "DQS3_B_c")
			(pintype "passive")
		)
		(pad "250" smd rect
			(at -30.37 -3.965 180)
			(size 0.3 1.5)
			(layers "F.Cu" "F.Mask" "F.Paste")
			(net 1 "GND")
			(pinfunction "VSS")
			(pintype "passive")
		)
		(pad "251" smd rect
			(at -30.62 -11.365 180)
			(size 0.3 1.5)
			(layers "F.Cu" "F.Mask" "F.Paste")
			(net 283 "/DDR5 SODIMM/B.DQS3_P")
			(pinfunction "DQS3_B_t")
			(pintype "passive")
		)
		(pad "252" smd rect
			(at -30.87 -3.965 180)
			(size 0.3 1.5)
			(layers "F.Cu" "F.Mask" "F.Paste")
			(net 284 "/DDR5 SODIMM/B.~{DM3}")
			(pinfunction "DM3_B_n")
			(pintype "passive")
		)
		(pad "253" smd rect
			(at -31.12 -11.365 180)
			(size 0.3 1.5)
			(layers "F.Cu" "F.Mask" "F.Paste")
			(net 1 "GND")
			(pinfunction "VSS")
			(pintype "passive")
		)
		(pad "254" smd rect
			(at -31.37 -3.965 180)
			(size 0.3 1.5)
			(layers "F.Cu" "F.Mask" "F.Paste")
			(net 1 "GND")
			(pinfunction "VSS")
			(pintype "passive")
		)
		(pad "255" smd rect
			(at -31.62 -11.365 180)
			(size 0.3 1.5)
			(layers "F.Cu" "F.Mask" "F.Paste")
			(net 286 "/DDR5 SODIMM/B.DQ28")
			(pinfunction "DQ28_B")
			(pintype "passive")
		)
		(pad "256" smd rect
			(at -31.87 -3.965 180)
			(size 0.3 1.5)
			(layers "F.Cu" "F.Mask" "F.Paste")
			(net 287 "/DDR5 SODIMM/B.DQ29")
			(pinfunction "DQ29_B")
			(pintype "passive")
		)
	)
)
